FILE_TYPE = MULTI_PHYS_TABLE;

PART 'ISL28022FRZT'

{========================================================================================}
:VALUE           | PART_TYPE | MATERIAL | PART_NUMBER    = STANDARD        | LIFECYCLE     | PART_NUMBER   | JEDEC_TYPE           | DESCRIPTION                 | MANUFTR | MANUF_PN        | RD_CMPLS_LVL | CMPLS_LVL | FROM_PJ    | CLASS | DIP_SMD | DATA                    | EE_CHECK_LIST | FP_ECN | PSL | CREATOR | STATUS | MSD | ESD_CDM | ESD_HBM | ESD_MM | PIN_LENGTH_SHORT_PIN | PIN_LENGTH_LONG_PIN | CREATEDAY  ;
{========================================================================================}
 'ISL28022FRZ-T' | 'SMLF'    | 'IC'     | 'AL028022003'(!) = ''               | ''               | 'AL028022003' |'QFN16_TH_0-5_3X3XH'| 'IC(16P)ISL28022FRZ-T(QFN)' | 'RTT'   | 'ISL28022FRZ-T' | 'EP(V1)'     | ''        | 'F09C-SEB' | 'IC'  | ''      | 'RTT_ISL28022FRZ-T.pdf' | ''            | ''     | ''  | ''      | ''     | ''  | ''      | ''      | ''     | '0 MILS'             | '0 MILS'            | '20210804'
 'ISL28022FRZ-T' | 'SMLF'    | 'EMPTY'  | 'AL028022003'(!) = ''               | ''               | 'AL028022003' |'QFN16_TH_0-5_3X3XH'| 'IC(16P)ISL28022FRZ-T(QFN)' | 'RTT'   | 'ISL28022FRZ-T' | 'EP(V1)'     | ''        | 'F09C-SEB' | 'IC'  | ''      | 'RTT_ISL28022FRZ-T.pdf' | ''            | ''     | ''  | ''      | ''     | ''  | ''      | ''      | ''     | '0 MILS'             | '0 MILS'            | '20210804'

END_PART

END.

